(kicad_pcb
	(version 20260206)
	(generator "pcbnew")
	(generator_version "10.0")
	(general
		(thickness 1.6)
		(legacy_teardrops no)
	)
	(paper "A4")
	(title_block
		(title "Bryce Canyon_R.DPB_16317-1_OCP.brd")
		(comment 1 "Bryce Canyon / footprints 1491-1496 of 2099")
	)
	(layers
		(0 "F.Cu" signal "TOP")
		(4 "In1.Cu" signal "L2GND")
		(6 "In2.Cu" signal "L3")
		(8 "In3.Cu" signal "L4VCC")
		(10 "In4.Cu" signal "L5VCC")
		(12 "In5.Cu" signal "L6")
		(14 "In6.Cu" signal "L7GND")
		(2 "B.Cu" signal "BOTTOM")
		(9 "F.Adhes" user "F.Adhesive")
		(11 "B.Adhes" user "B.Adhesive")
		(13 "F.Paste" user "Package Geometry/Pastemask Top")
		(15 "B.Paste" user "Package Geometry/Pastemask Bottom")
		(5 "F.SilkS" user "Ref Des/Silkscreen Top")
		(7 "B.SilkS" user "Ref Des/Silkscreen Bottom")
		(1 "F.Mask" user "Board Geometry/Soldermask Top")
		(3 "B.Mask" user "Board Geometry/Soldermask Bottom")
		(17 "Dwgs.User" user "User.Drawings")
		(19 "Cmts.User" user "User.Comments")
		(21 "Eco1.User" user "User.Eco1")
		(23 "Eco2.User" user "User.Eco2")
		(25 "Edge.Cuts" user "Board Geometry/Outline")
		(27 "Margin" user)
		(31 "F.CrtYd" user "Package Geometry/Place Bound Top")
		(29 "B.CrtYd" user "Package Geometry/Place Bound Bottom")
		(35 "F.Fab" user "Ref Des/Assembly Top")
		(33 "B.Fab" user "Ref Des/Assembly Bottom")
	)
	(footprint ""
		(layer "F.Cu")
		(at 220.853 -225.425 90)
		(property "Reference" "C4"
			(at 0 0 90)
			(layer "F.SilkS")
			(hide yes)
			(effects
				(font
					(size 1.27 1.27)
				)
			)
		)
		(property "Value" "SCD1U16V2KX-3GP"
			(at 1.1811 -2.7051 90)
			(unlocked yes)
			(layer "F.Fab")
			(hide yes)
			(effects
				(font
					(size 1.016 1.016)
					(thickness 0.1524)
				)
			)
		)
		(property "Device Type" "C402H22"
			(at 1.1811 -4.2291 90)
			(unlocked yes)
			(layer "F.Fab")
			(hide yes)
			(effects
				(font
					(size 1.016 1.016)
					(thickness 0.1524)
				)
			)
		)
		(duplicate_pad_numbers_are_jumpers no)
		(fp_rect
			(start -0.4318 0.9525)
			(end 0.4318 -0.9525)
			(stroke
				(width 0)
				(type default)
			)
			(fill no)
			(layer "F.CrtYd")
		)
		(fp_rect
			(start -0.4318 0.9525)
			(end 0.4318 -0.9525)
			(stroke
				(width 0)
				(type default)
			)
			(fill no)
			(layer "F.Fab")
		)
		(pad "1" smd custom
			(at 0 -0.4445 90)
			(size 0.1524 0.1524)
			(layers "F.Cu" "F.Mask" "F.Paste")
			(net "P3V3_STBY_B")
			(options
				(clearance outline)
				(anchor circle)
			)
			(primitives
				(gr_poly
					(pts
						(arc
							(start 0.3048 -0.2032)
							(mid 0.275042 -0.275042)
							(end 0.2032 -0.3048)
						)
						(arc
							(start -0.2032 -0.3048)
							(mid -0.275042 -0.275042)
							(end -0.3048 -0.2032)
						)
						(arc
							(start -0.3048 0.2032)
							(mid -0.275042 0.275042)
							(end -0.2032 0.3048)
						)
						(arc
							(start 0.2032 0.3048)
							(mid 0.275042 0.275042)
							(end 0.3048 0.2032)
						)
					)
					(width 0)
					(fill yes)
				)
			)
		)
		(pad "2" smd custom
			(at 0 0.4445 90)
			(size 0.1524 0.1524)
			(layers "F.Cu" "F.Mask" "F.Paste")
			(net "GND")
			(options
				(clearance outline)
				(anchor circle)
			)
			(primitives
				(gr_poly
					(pts
						(arc
							(start 0.3048 -0.2032)
							(mid 0.275042 -0.275042)
							(end 0.2032 -0.3048)
						)
						(arc
							(start -0.2032 -0.3048)
							(mid -0.275042 -0.275042)
							(end -0.3048 -0.2032)
						)
						(arc
							(start -0.3048 0.2032)
							(mid -0.275042 0.275042)
							(end -0.2032 0.3048)
						)
						(arc
							(start 0.2032 0.3048)
							(mid 0.275042 0.275042)
							(end 0.3048 0.2032)
						)
					)
					(width 0)
					(fill yes)
				)
			)
		)
	)
	(footprint ""
		(layer "F.Cu")
		(at 259.588 -213.995 -90)
		(property "Reference" "R123"
			(at 0 0 270)
			(layer "F.SilkS")
			(hide yes)
			(effects
				(font
					(size 1.27 1.27)
				)
			)
		)
		(property "Value" "4K7R2F-GP"
			(at 0.064008 -3.993896 270)
			(unlocked yes)
			(layer "F.Fab")
			(hide yes)
			(effects
				(font
					(size 1.016 1.016)
					(thickness 0.1524)
				)
			)
		)
		(property "Device Type" "R402H16"
			(at 0.064008 -5.517896 270)
			(unlocked yes)
			(layer "F.Fab")
			(hide yes)
			(effects
				(font
					(size 1.016 1.016)
					(thickness 0.1524)
				)
			)
		)
		(duplicate_pad_numbers_are_jumpers no)
		(fp_line
			(start -0.508 -0.9398)
			(end -0.508 0.9398)
			(stroke
				(width 0.1524)
				(type default)
			)
			(layer "F.SilkS")
		)
		(fp_line
			(start 0.508 -0.9398)
			(end -0.508 -0.9398)
			(stroke
				(width 0.1524)
				(type default)
			)
			(layer "F.SilkS")
		)
		(fp_rect
			(start -0.508 0.9398)
			(end 0.508 -0.9398)
			(stroke
				(width 0)
				(type default)
			)
			(fill no)
			(layer "F.CrtYd")
		)
		(fp_rect
			(start -0.508 0.9398)
			(end 0.508 -0.9398)
			(stroke
				(width 0)
				(type default)
			)
			(fill no)
			(layer "F.Fab")
		)
		(pad "1" smd custom
			(at 0 -0.4445 270)
			(size 0.1397 0.1397)
			(layers "F.Cu" "F.Mask" "F.Paste")
			(net "P3V3_STBY_B")
			(options
				(clearance outline)
				(anchor circle)
			)
			(primitives
				(gr_poly
					(pts
						(arc
							(start -0.1778 -0.2794)
							(mid -0.249642 -0.249642)
							(end -0.2794 -0.1778)
						)
						(arc
							(start -0.2794 0.1778)
							(mid -0.249642 0.249642)
							(end -0.1778 0.2794)
						)
						(arc
							(start 0.1778 0.2794)
							(mid 0.249642 0.249642)
							(end 0.2794 0.1778)
						)
						(arc
							(start 0.2794 -0.1778)
							(mid 0.249642 -0.249642)
							(end 0.1778 -0.2794)
						)
					)
					(width 0)
					(fill yes)
				)
			)
		)
		(pad "2" smd custom
			(at 0 0.4445 270)
			(size 0.1397 0.1397)
			(layers "F.Cu" "F.Mask" "F.Paste")
			(net "VOL_SEN_INT_N")
			(options
				(clearance outline)
				(anchor circle)
			)
			(primitives
				(gr_poly
					(pts
						(arc
							(start -0.1778 -0.2794)
							(mid -0.249642 -0.249642)
							(end -0.2794 -0.1778)
						)
						(arc
							(start -0.2794 0.1778)
							(mid -0.249642 0.249642)
							(end -0.1778 0.2794)
						)
						(arc
							(start 0.1778 0.2794)
							(mid 0.249642 0.249642)
							(end 0.2794 0.1778)
						)
						(arc
							(start 0.2794 -0.1778)
							(mid 0.249642 -0.249642)
							(end 0.1778 -0.2794)
						)
					)
					(width 0)
					(fill yes)
				)
			)
		)
	)
	(footprint ""
		(layer "F.Cu")
		(at 438.104026 -214.757 180)
		(property "Reference" "Q229"
			(at 0 0 180)
			(layer "F.SilkS")
			(hide yes)
			(effects
				(font
					(size 1.27 1.27)
				)
			)
		)
		(property "Value" "2N7002K-2-GP"
			(at 0.127 -8.9662 180)
			(unlocked yes)
			(layer "F.Fab")
			(hide yes)
			(effects
				(font
					(size 1.016 1.016)
					(thickness 0.1524)
				)
			)
		)
		(property "Device Type" "SOT23DGS2D4H44"
			(at 0.127 -10.4902 180)
			(unlocked yes)
			(layer "F.Fab")
			(hide yes)
			(effects
				(font
					(size 1.016 1.016)
					(thickness 0.1524)
				)
			)
		)
		(duplicate_pad_numbers_are_jumpers no)
		(fp_line
			(start 1.651 1.778)
			(end 1.651 -1.778)
			(stroke
				(width 0.1524)
				(type default)
			)
			(layer "F.SilkS")
		)
		(fp_line
			(start 1.651 -1.778)
			(end -1.651 -1.778)
			(stroke
				(width 0.1524)
				(type default)
			)
			(layer "F.SilkS")
		)
		(fp_line
			(start -1.651 1.778)
			(end 1.651 1.778)
			(stroke
				(width 0.1524)
				(type default)
			)
			(layer "F.SilkS")
		)
		(fp_line
			(start -1.651 -1.778)
			(end -1.651 1.778)
			(stroke
				(width 0.1524)
				(type default)
			)
			(layer "F.SilkS")
		)
		(fp_poly
			(pts
				(xy -1.778 1.8796) (xy -1.778 -1.8796) (xy 1.778 -1.8796) (xy 1.778 1.8796)
			)
			(stroke
				(width 0)
				(type default)
			)
			(fill no)
			(layer "F.CrtYd")
		)
		(fp_poly
			(pts
				(xy -1.778 1.8796) (xy -1.778 -1.8796) (xy 1.778 -1.8796) (xy 1.778 1.8796)
			)
			(stroke
				(width 0)
				(type default)
			)
			(fill no)
			(layer "F.Fab")
		)
		(pad "D" smd custom
			(at 0 -0.9525 180)
			(size 0.1905 0.1905)
			(layers "F.Cu" "F.Mask" "F.Paste")
			(net "FLT_HDD10_N")
			(options
				(clearance outline)
				(anchor circle)
			)
			(primitives
				(gr_poly
					(pts
						(arc
							(start -0.1778 0.5715)
							(mid -0.321484 0.511984)
							(end -0.381 0.3683)
						)
						(arc
							(start -0.381 -0.3683)
							(mid -0.321484 -0.511984)
							(end -0.1778 -0.5715)
						)
						(arc
							(start 0.1778 -0.5715)
							(mid 0.321484 -0.511984)
							(end 0.381 -0.3683)
						)
						(arc
							(start 0.381 0.3683)
							(mid 0.321484 0.511984)
							(end 0.1778 0.5715)
						)
					)
					(width 0)
					(fill yes)
				)
			)
		)
		(pad "G" smd custom
			(at -0.98425 0.9525 180)
			(size 0.1905 0.1905)
			(layers "F.Cu" "F.Mask" "F.Paste")
			(net "DRIVE_B_10_FLT_LED")
			(options
				(clearance outline)
				(anchor circle)
			)
			(primitives
				(gr_poly
					(pts
						(arc
							(start -0.1778 0.5715)
							(mid -0.321484 0.511984)
							(end -0.381 0.3683)
						)
						(arc
							(start -0.381 -0.3683)
							(mid -0.321484 -0.511984)
							(end -0.1778 -0.5715)
						)
						(arc
							(start 0.1778 -0.5715)
							(mid 0.321484 -0.511984)
							(end 0.381 -0.3683)
						)
						(arc
							(start 0.381 0.3683)
							(mid 0.321484 0.511984)
							(end 0.1778 0.5715)
						)
					)
					(width 0)
					(fill yes)
				)
			)
		)
		(pad "S" smd custom
			(at 0.98425 0.9525 180)
			(size 0.1905 0.1905)
			(layers "F.Cu" "F.Mask" "F.Paste")
			(net "GND")
			(options
				(clearance outline)
				(anchor circle)
			)
			(primitives
				(gr_poly
					(pts
						(arc
							(start -0.1778 0.5715)
							(mid -0.321484 0.511984)
							(end -0.381 0.3683)
						)
						(arc
							(start -0.381 -0.3683)
							(mid -0.321484 -0.511984)
							(end -0.1778 -0.5715)
						)
						(arc
							(start 0.1778 -0.5715)
							(mid 0.321484 -0.511984)
							(end 0.381 -0.3683)
						)
						(arc
							(start 0.381 0.3683)
							(mid 0.321484 0.511984)
							(end 0.1778 0.5715)
						)
					)
					(width 0)
					(fill yes)
				)
			)
		)
	)
	(footprint ""
		(layer "F.Cu")
		(at 209.92338 -235.18622)
		(property "Reference" "R40"
			(at 0 0 0)
			(layer "F.SilkS")
			(hide yes)
			(effects
				(font
					(size 1.27 1.27)
				)
			)
		)
		(property "Value" "0R2J-2-GP"
			(at 0.064008 -3.993896 0)
			(unlocked yes)
			(layer "F.Fab")
			(hide yes)
			(effects
				(font
					(size 1.016 1.016)
					(thickness 0.1524)
				)
			)
		)
		(property "Device Type" "R402H16"
			(at 0.064008 -5.517896 0)
			(unlocked yes)
			(layer "F.Fab")
			(hide yes)
			(effects
				(font
					(size 1.016 1.016)
					(thickness 0.1524)
				)
			)
		)
		(duplicate_pad_numbers_are_jumpers no)
		(fp_line
			(start -0.508 -0.9398)
			(end -0.508 0.9398)
			(stroke
				(width 0.1524)
				(type default)
			)
			(layer "F.SilkS")
		)
		(fp_line
			(start 0.508 -0.9398)
			(end -0.508 -0.9398)
			(stroke
				(width 0.1524)
				(type default)
			)
			(layer "F.SilkS")
		)
		(fp_rect
			(start -0.508 0.9398)
			(end 0.508 -0.9398)
			(stroke
				(width 0)
				(type default)
			)
			(fill no)
			(layer "F.CrtYd")
		)
		(fp_rect
			(start -0.508 0.9398)
			(end 0.508 -0.9398)
			(stroke
				(width 0)
				(type default)
			)
			(fill no)
			(layer "F.Fab")
		)
		(pad "1" smd custom
			(at 0 -0.4445)
			(size 0.1397 0.1397)
			(layers "F.Cu" "F.Mask" "F.Paste")
			(net "IO_EXP4_SCL")
			(options
				(clearance outline)
				(anchor circle)
			)
			(primitives
				(gr_poly
					(pts
						(arc
							(start -0.1778 -0.2794)
							(mid -0.249642 -0.249642)
							(end -0.2794 -0.1778)
						)
						(arc
							(start -0.2794 0.1778)
							(mid -0.249642 0.249642)
							(end -0.1778 0.2794)
						)
						(arc
							(start 0.1778 0.2794)
							(mid 0.249642 0.249642)
							(end 0.2794 0.1778)
						)
						(arc
							(start 0.2794 -0.1778)
							(mid 0.249642 -0.249642)
							(end 0.1778 -0.2794)
						)
					)
					(width 0)
					(fill yes)
				)
			)
		)
		(pad "2" smd custom
			(at 0 0.4445)
			(size 0.1397 0.1397)
			(layers "F.Cu" "F.Mask" "F.Paste")
			(net "I2C_DRIVE_B_INS_SCL")
			(options
				(clearance outline)
				(anchor circle)
			)
			(primitives
				(gr_poly
					(pts
						(arc
							(start -0.1778 -0.2794)
							(mid -0.249642 -0.249642)
							(end -0.2794 -0.1778)
						)
						(arc
							(start -0.2794 0.1778)
							(mid -0.249642 0.249642)
							(end -0.1778 0.2794)
						)
						(arc
							(start 0.1778 0.2794)
							(mid 0.249642 0.249642)
							(end 0.2794 0.1778)
						)
						(arc
							(start 0.2794 -0.1778)
							(mid 0.249642 -0.249642)
							(end 0.1778 -0.2794)
						)
					)
					(width 0)
					(fill yes)
				)
			)
		)
	)
	(footprint ""
		(layer "F.Cu")
		(at 77.5716 -99.7712 180)
		(property "Reference" "Q233"
			(at 0 0 180)
			(layer "F.SilkS")
			(hide yes)
			(effects
				(font
					(size 1.27 1.27)
				)
			)
		)
		(property "Value" "2N7002K-2-GP"
			(at 0.127 -8.9662 180)
			(unlocked yes)
			(layer "F.Fab")
			(hide yes)
			(effects
				(font
					(size 1.016 1.016)
					(thickness 0.1524)
				)
			)
		)
		(property "Device Type" "SOT23DGS2D4H44"
			(at 0.127 -10.4902 180)
			(unlocked yes)
			(layer "F.Fab")
			(hide yes)
			(effects
				(font
					(size 1.016 1.016)
					(thickness 0.1524)
				)
			)
		)
		(duplicate_pad_numbers_are_jumpers no)
		(fp_line
			(start 1.651 1.778)
			(end 1.651 -1.778)
			(stroke
				(width 0.1524)
				(type default)
			)
			(layer "F.SilkS")
		)
		(fp_line
			(start 1.651 -1.778)
			(end -1.651 -1.778)
			(stroke
				(width 0.1524)
				(type default)
			)
			(layer "F.SilkS")
		)
		(fp_line
			(start -1.651 1.778)
			(end 1.651 1.778)
			(stroke
				(width 0.1524)
				(type default)
			)
			(layer "F.SilkS")
		)
		(fp_line
			(start -1.651 -1.778)
			(end -1.651 1.778)
			(stroke
				(width 0.1524)
				(type default)
			)
			(layer "F.SilkS")
		)
		(fp_poly
			(pts
				(xy -1.778 1.8796) (xy -1.778 -1.8796) (xy 1.778 -1.8796) (xy 1.778 1.8796)
			)
			(stroke
				(width 0)
				(type default)
			)
			(fill no)
			(layer "F.CrtYd")
		)
		(fp_poly
			(pts
				(xy -1.778 1.8796) (xy -1.778 -1.8796) (xy 1.778 -1.8796) (xy 1.778 1.8796)
			)
			(stroke
				(width 0)
				(type default)
			)
			(fill no)
			(layer "F.Fab")
		)
		(pad "D" smd custom
			(at 0 -0.9525 180)
			(size 0.1905 0.1905)
			(layers "F.Cu" "F.Mask" "F.Paste")
			(net "FLT_HDD14_N")
			(options
				(clearance outline)
				(anchor circle)
			)
			(primitives
				(gr_poly
					(pts
						(arc
							(start -0.1778 0.5715)
							(mid -0.321484 0.511984)
							(end -0.381 0.3683)
						)
						(arc
							(start -0.381 -0.3683)
							(mid -0.321484 -0.511984)
							(end -0.1778 -0.5715)
						)
						(arc
							(start 0.1778 -0.5715)
							(mid 0.321484 -0.511984)
							(end 0.381 -0.3683)
						)
						(arc
							(start 0.381 0.3683)
							(mid 0.321484 0.511984)
							(end 0.1778 0.5715)
						)
					)
					(width 0)
					(fill yes)
				)
			)
		)
		(pad "G" smd custom
			(at -0.98425 0.9525 180)
			(size 0.1905 0.1905)
			(layers "F.Cu" "F.Mask" "F.Paste")
			(net "DRIVE_B_14_FLT_LED")
			(options
				(clearance outline)
				(anchor circle)
			)
			(primitives
				(gr_poly
					(pts
						(arc
							(start -0.1778 0.5715)
							(mid -0.321484 0.511984)
							(end -0.381 0.3683)
						)
						(arc
							(start -0.381 -0.3683)
							(mid -0.321484 -0.511984)
							(end -0.1778 -0.5715)
						)
						(arc
							(start 0.1778 -0.5715)
							(mid 0.321484 -0.511984)
							(end 0.381 -0.3683)
						)
						(arc
							(start 0.381 0.3683)
							(mid 0.321484 0.511984)
							(end 0.1778 0.5715)
						)
					)
					(width 0)
					(fill yes)
				)
			)
		)
		(pad "S" smd custom
			(at 0.98425 0.9525 180)
			(size 0.1905 0.1905)
			(layers "F.Cu" "F.Mask" "F.Paste")
			(net "GND")
			(options
				(clearance outline)
				(anchor circle)
			)
			(primitives
				(gr_poly
					(pts
						(arc
							(start -0.1778 0.5715)
							(mid -0.321484 0.511984)
							(end -0.381 0.3683)
						)
						(arc
							(start -0.381 -0.3683)
							(mid -0.321484 -0.511984)
							(end -0.1778 -0.5715)
						)
						(arc
							(start 0.1778 -0.5715)
							(mid 0.321484 -0.511984)
							(end 0.381 -0.3683)
						)
						(arc
							(start 0.381 0.3683)
							(mid 0.321484 0.511984)
							(end 0.1778 0.5715)
						)
					)
					(width 0)
					(fill yes)
				)
			)
		)
	)
	(footprint ""
		(layer "F.Cu")
		(at 251.941838 -227.34651 -90)
		(property "Reference" "R132"
			(at 0 0 270)
			(layer "F.SilkS")
			(hide yes)
			(effects
				(font
					(size 1.27 1.27)
				)
			)
		)
		(property "Value" "10KR2F-2-GP"
			(at 0.064008 -3.993896 270)
			(unlocked yes)
			(layer "F.Fab")
			(hide yes)
			(effects
				(font
					(size 1.016 1.016)
					(thickness 0.1524)
				)
			)
		)
		(property "Device Type" "R402H16"
			(at 0.064008 -5.517896 270)
			(unlocked yes)
			(layer "F.Fab")
			(hide yes)
			(effects
				(font
					(size 1.016 1.016)
					(thickness 0.1524)
				)
			)
		)
		(duplicate_pad_numbers_are_jumpers no)
		(fp_line
			(start -0.508 -0.9398)
			(end -0.508 0.9398)
			(stroke
				(width 0.1524)
				(type default)
			)
			(layer "F.SilkS")
		)
		(fp_line
			(start 0.508 -0.9398)
			(end -0.508 -0.9398)
			(stroke
				(width 0.1524)
				(type default)
			)
			(layer "F.SilkS")
		)
		(fp_rect
			(start -0.508 0.9398)
			(end 0.508 -0.9398)
			(stroke
				(width 0)
				(type default)
			)
			(fill no)
			(layer "F.CrtYd")
		)
		(fp_rect
			(start -0.508 0.9398)
			(end 0.508 -0.9398)
			(stroke
				(width 0)
				(type default)
			)
			(fill no)
			(layer "F.Fab")
		)
		(pad "1" smd custom
			(at 0 -0.4445 270)
			(size 0.1397 0.1397)
			(layers "F.Cu" "F.Mask" "F.Paste")
			(net "P3V3_SENSE")
			(options
				(clearance outline)
				(anchor circle)
			)
			(primitives
				(gr_poly
					(pts
						(arc
							(start -0.1778 -0.2794)
							(mid -0.249642 -0.249642)
							(end -0.2794 -0.1778)
						)
						(arc
							(start -0.2794 0.1778)
							(mid -0.249642 0.249642)
							(end -0.1778 0.2794)
						)
						(arc
							(start 0.1778 0.2794)
							(mid 0.249642 0.249642)
							(end 0.2794 0.1778)
						)
						(arc
							(start 0.2794 -0.1778)
							(mid 0.249642 -0.249642)
							(end 0.1778 -0.2794)
						)
					)
					(width 0)
					(fill yes)
				)
			)
		)
		(pad "2" smd custom
			(at 0 0.4445 270)
			(size 0.1397 0.1397)
			(layers "F.Cu" "F.Mask" "F.Paste")
			(net "GND")
			(options
				(clearance outline)
				(anchor circle)
			)
			(primitives
				(gr_poly
					(pts
						(arc
							(start -0.1778 -0.2794)
							(mid -0.249642 -0.249642)
							(end -0.2794 -0.1778)
						)
						(arc
							(start -0.2794 0.1778)
							(mid -0.249642 0.249642)
							(end -0.1778 0.2794)
						)
						(arc
							(start 0.1778 0.2794)
							(mid 0.249642 0.249642)
							(end 0.2794 0.1778)
						)
						(arc
							(start 0.2794 -0.1778)
							(mid 0.249642 -0.249642)
							(end 0.1778 -0.2794)
						)
					)
					(width 0)
					(fill yes)
				)
			)
		)
	)
)
